(kicad_pcb
	(version 20260206)
	(generator "pcbnew")
	(generator_version "10.0")
	(general
		(thickness 1.6)
		(legacy_teardrops no)
	)
	(paper "A4")
	(title_block
		(title "04192023_DAF0TMB3IC0_F0TG_MB_C_brd_V02_OCP.brd")
		(comment 1 "Grand Teton / footprints 4556-4561 of 8354")
	)
	(layers
		(0 "F.Cu" signal "TOP")
		(4 "In1.Cu" signal "GND")
		(6 "In2.Cu" signal "IN1")
		(8 "In3.Cu" signal "GND1")
		(10 "In4.Cu" signal "IN2")
		(12 "In5.Cu" signal "GND2")
		(14 "In6.Cu" signal "IN3")
		(16 "In7.Cu" signal "GND3")
		(18 "In8.Cu" signal "VCC")
		(20 "In9.Cu" signal "VCC1")
		(22 "In10.Cu" signal "GND4")
		(24 "In11.Cu" signal "IN4")
		(26 "In12.Cu" signal "GND5")
		(28 "In13.Cu" signal "IN5")
		(30 "In14.Cu" signal "GND6")
		(32 "In15.Cu" signal "IN6")
		(34 "In16.Cu" signal "GND7")
		(2 "B.Cu" signal "BOTTOM")
		(9 "F.Adhes" user "F.Adhesive")
		(11 "B.Adhes" user "B.Adhesive")
		(13 "F.Paste" user "Package Geometry/Pastemask Top")
		(15 "B.Paste" user "Package Geometry/Pastemask Bottom")
		(5 "F.SilkS" user "Ref Des/Silkscreen Top")
		(7 "B.SilkS" user "Ref Des/Silkscreen Bottom")
		(1 "F.Mask" user "Board Geometry/Soldermask Top")
		(3 "B.Mask" user "Board Geometry/Soldermask Bottom")
		(17 "Dwgs.User" user "User.Drawings")
		(19 "Cmts.User" user "User.Comments")
		(21 "Eco1.User" user "User.Eco1")
		(23 "Eco2.User" user "User.Eco2")
		(25 "Edge.Cuts" user "Board Geometry/Outline")
		(27 "Margin" user)
		(31 "F.CrtYd" user "Package Geometry/Place Bound Top")
		(29 "B.CrtYd" user "Package Geometry/Place Bound Bottom")
		(35 "F.Fab" user "Ref Des/Assembly Top")
		(33 "B.Fab" user "Ref Des/Assembly Bottom")
	)
	(footprint ""
		(layer "F.Cu")
		(at 14.257782 -416.050984 90)
		(property "Reference" "PR6541"
			(at 0 0 90)
			(layer "F.SilkS")
			(hide yes)
			(effects
				(font
					(size 1.27 1.27)
				)
			)
		)
		(property "Value" ""
			(at 0 0 90)
			(layer "F.Fab")
			(effects
				(font
					(size 1.27 1.27)
				)
			)
		)
		(duplicate_pad_numbers_are_jumpers no)
		(fp_line
			(start 0.7874 -0.4064)
			(end 0.7874 0.4064)
			(stroke
				(width 0.1524)
				(type default)
			)
			(layer "F.SilkS")
		)
		(fp_line
			(start -0.7874 -0.4064)
			(end 0.7874 -0.4064)
			(stroke
				(width 0.1524)
				(type default)
			)
			(layer "F.SilkS")
		)
		(fp_line
			(start 0.7874 0.4064)
			(end -0.7874 0.4064)
			(stroke
				(width 0.1524)
				(type default)
			)
			(layer "F.SilkS")
		)
		(fp_line
			(start -0.7874 0.4064)
			(end -0.7874 -0.4064)
			(stroke
				(width 0.1524)
				(type default)
			)
			(layer "F.SilkS")
		)
		(fp_line
			(start -0.12065 -0.305054)
			(end -0.12065 -0.2794)
			(stroke
				(width 0.1)
				(type default)
			)
			(layer "F.Fab")
		)
		(fp_line
			(start -0.67945 -0.305054)
			(end -0.12065 -0.305054)
			(stroke
				(width 0.1)
				(type default)
			)
			(layer "F.Fab")
		)
		(fp_line
			(start 0.67945 -0.3048)
			(end 0.67945 0.3048)
			(stroke
				(width 0.1)
				(type default)
			)
			(layer "F.Fab")
		)
		(fp_line
			(start 0.12065 -0.3048)
			(end 0.67945 -0.3048)
			(stroke
				(width 0.1)
				(type default)
			)
			(layer "F.Fab")
		)
		(fp_line
			(start 0.12065 -0.2794)
			(end 0.12065 -0.3048)
			(stroke
				(width 0.1)
				(type default)
			)
			(layer "F.Fab")
		)
		(fp_line
			(start -0.12065 -0.2794)
			(end 0.12065 -0.2794)
			(stroke
				(width 0.1)
				(type default)
			)
			(layer "F.Fab")
		)
		(fp_line
			(start 0.120396 0.2794)
			(end -0.12065 0.2794)
			(stroke
				(width 0.1)
				(type default)
			)
			(layer "F.Fab")
		)
		(fp_line
			(start -0.12065 0.2794)
			(end -0.12065 0.3048)
			(stroke
				(width 0.1)
				(type default)
			)
			(layer "F.Fab")
		)
		(fp_line
			(start 0.67945 0.3048)
			(end 0.120396 0.3048)
			(stroke
				(width 0.1)
				(type default)
			)
			(layer "F.Fab")
		)
		(fp_line
			(start 0.120396 0.3048)
			(end 0.120396 0.2794)
			(stroke
				(width 0.1)
				(type default)
			)
			(layer "F.Fab")
		)
		(fp_line
			(start -0.12065 0.3048)
			(end -0.67945 0.3048)
			(stroke
				(width 0.1)
				(type default)
			)
			(layer "F.Fab")
		)
		(fp_line
			(start -0.67945 0.3048)
			(end -0.67945 -0.305054)
			(stroke
				(width 0.1)
				(type default)
			)
			(layer "F.Fab")
		)
		(pad "1" smd circle
			(at -0.40005 0 90)
			(size 0 0)
			(layers "F.Cu" "F.Mask" "F.Paste")
			(net "NC_P0V9_RETIMER_CPU1_IMON5")
		)
		(pad "2" smd circle
			(at 0.40005 0 90)
			(size 0 0)
			(layers "F.Cu" "F.Mask" "F.Paste")
			(net "GND")
		)
	)
	(footprint ""
		(layer "F.Cu")
		(at 16.039592 -139.25804 -90)
		(property "Reference" "R4076"
			(at 0 0 270)
			(layer "F.SilkS")
			(hide yes)
			(effects
				(font
					(size 1.27 1.27)
				)
			)
		)
		(property "Value" ""
			(at 0 0 270)
			(layer "F.Fab")
			(effects
				(font
					(size 1.27 1.27)
				)
			)
		)
		(duplicate_pad_numbers_are_jumpers no)
		(fp_line
			(start -0.7874 0.4064)
			(end -0.7874 -0.4064)
			(stroke
				(width 0.1524)
				(type default)
			)
			(layer "F.SilkS")
		)
		(fp_line
			(start 0.7874 0.4064)
			(end -0.7874 0.4064)
			(stroke
				(width 0.1524)
				(type default)
			)
			(layer "F.SilkS")
		)
		(fp_line
			(start -0.7874 -0.4064)
			(end 0.7874 -0.4064)
			(stroke
				(width 0.1524)
				(type default)
			)
			(layer "F.SilkS")
		)
		(fp_line
			(start 0.7874 -0.4064)
			(end 0.7874 0.4064)
			(stroke
				(width 0.1524)
				(type default)
			)
			(layer "F.SilkS")
		)
		(fp_line
			(start -0.67945 0.3048)
			(end -0.67945 -0.305054)
			(stroke
				(width 0.1)
				(type default)
			)
			(layer "F.Fab")
		)
		(fp_line
			(start -0.12065 0.3048)
			(end -0.67945 0.3048)
			(stroke
				(width 0.1)
				(type default)
			)
			(layer "F.Fab")
		)
		(fp_line
			(start 0.120396 0.3048)
			(end 0.120396 0.2794)
			(stroke
				(width 0.1)
				(type default)
			)
			(layer "F.Fab")
		)
		(fp_line
			(start 0.67945 0.3048)
			(end 0.120396 0.3048)
			(stroke
				(width 0.1)
				(type default)
			)
			(layer "F.Fab")
		)
		(fp_line
			(start -0.12065 0.2794)
			(end -0.12065 0.3048)
			(stroke
				(width 0.1)
				(type default)
			)
			(layer "F.Fab")
		)
		(fp_line
			(start 0.120396 0.2794)
			(end -0.12065 0.2794)
			(stroke
				(width 0.1)
				(type default)
			)
			(layer "F.Fab")
		)
		(fp_line
			(start -0.12065 -0.2794)
			(end 0.12065 -0.2794)
			(stroke
				(width 0.1)
				(type default)
			)
			(layer "F.Fab")
		)
		(fp_line
			(start 0.12065 -0.2794)
			(end 0.12065 -0.3048)
			(stroke
				(width 0.1)
				(type default)
			)
			(layer "F.Fab")
		)
		(fp_line
			(start 0.12065 -0.3048)
			(end 0.67945 -0.3048)
			(stroke
				(width 0.1)
				(type default)
			)
			(layer "F.Fab")
		)
		(fp_line
			(start 0.67945 -0.3048)
			(end 0.67945 0.3048)
			(stroke
				(width 0.1)
				(type default)
			)
			(layer "F.Fab")
		)
		(fp_line
			(start -0.67945 -0.305054)
			(end -0.12065 -0.305054)
			(stroke
				(width 0.1)
				(type default)
			)
			(layer "F.Fab")
		)
		(fp_line
			(start -0.12065 -0.305054)
			(end -0.12065 -0.2794)
			(stroke
				(width 0.1)
				(type default)
			)
			(layer "F.Fab")
		)
		(pad "1" smd circle
			(at -0.40005 0 270)
			(size 0 0)
			(layers "F.Cu" "F.Mask" "F.Paste")
			(net "CLK_GEN2_GPU_FPGA_OE_OR_N")
		)
		(pad "2" smd circle
			(at 0.40005 0 270)
			(size 0 0)
			(layers "F.Cu" "F.Mask" "F.Paste")
			(net "CLK_GEN2_GPU_OE_N")
		)
	)
	(footprint ""
		(layer "F.Cu")
		(at 422.74617 -153.594562)
		(property "Reference" "PC1845"
			(at -1.86817 3.761232 0)
			(unlocked yes)
			(layer "F.SilkS")
			(effects
				(font
					(size 0.7874 0.5842)
					(thickness 0.1524)
				)
				(justify left)
			)
		)
		(property "Value" ""
			(at 0 0 0)
			(layer "F.Fab")
			(effects
				(font
					(size 1.27 1.27)
				)
			)
		)
		(duplicate_pad_numbers_are_jumpers no)
		(fp_line
			(start -2.750058 -1.988058)
			(end -2.750058 -0.9398)
			(stroke
				(width 0.1524)
				(type default)
			)
			(layer "F.SilkS")
		)
		(fp_line
			(start -2.750058 0.9398)
			(end -2.750058 1.988058)
			(stroke
				(width 0.1524)
				(type default)
			)
			(layer "F.SilkS")
		)
		(fp_line
			(start -2.750058 1.988058)
			(end -1.988058 2.750058)
			(stroke
				(width 0.1524)
				(type default)
			)
			(layer "F.SilkS")
		)
		(fp_line
			(start -1.988058 -2.750058)
			(end -2.750058 -1.988058)
			(stroke
				(width 0.1524)
				(type default)
			)
			(layer "F.SilkS")
		)
		(fp_line
			(start -1.988058 2.750058)
			(end 2.750058 2.750058)
			(stroke
				(width 0.1524)
				(type default)
			)
			(layer "F.SilkS")
		)
		(fp_line
			(start 2.750058 -2.750058)
			(end -1.988058 -2.750058)
			(stroke
				(width 0.1524)
				(type default)
			)
			(layer "F.SilkS")
		)
		(fp_line
			(start 2.750058 -0.9398)
			(end 2.750058 -2.750058)
			(stroke
				(width 0.1524)
				(type default)
			)
			(layer "F.SilkS")
		)
		(fp_line
			(start 2.750058 2.750058)
			(end 2.750058 0.9398)
			(stroke
				(width 0.1524)
				(type default)
			)
			(layer "F.SilkS")
		)
		(fp_line
			(start -2.750058 -2.750058)
			(end -2.750058 2.750058)
			(stroke
				(width 0.1)
				(type default)
			)
			(layer "F.Fab")
		)
		(fp_line
			(start -2.750058 2.750058)
			(end 2.750058 2.750058)
			(stroke
				(width 0.1)
				(type default)
			)
			(layer "F.Fab")
		)
		(fp_line
			(start 2.750058 -2.750058)
			(end -2.750058 -2.750058)
			(stroke
				(width 0.1)
				(type default)
			)
			(layer "F.Fab")
		)
		(fp_line
			(start 2.750058 2.750058)
			(end 2.750058 -2.750058)
			(stroke
				(width 0.1)
				(type default)
			)
			(layer "F.Fab")
		)
		(pad "1" smd rect
			(at -2.199894 0 90)
			(size 1.6002 3.0226)
			(layers "F.Cu" "F.Mask" "F.Paste")
			(net "P5V_AUX")
		)
		(pad "2" smd rect
			(at 2.199894 0 90)
			(size 1.6002 3.0226)
			(layers "F.Cu" "F.Mask" "F.Paste")
			(net "GND")
		)
	)
	(footprint ""
		(layer "F.Cu")
		(at 120.68175 -26.815796)
		(property "Reference" "R6265"
			(at 0 0 0)
			(layer "F.SilkS")
			(hide yes)
			(effects
				(font
					(size 1.27 1.27)
				)
			)
		)
		(property "Value" ""
			(at 0 0 0)
			(layer "F.Fab")
			(effects
				(font
					(size 1.27 1.27)
				)
			)
		)
		(duplicate_pad_numbers_are_jumpers no)
		(fp_line
			(start -0.7874 -0.4064)
			(end 0.7874 -0.4064)
			(stroke
				(width 0.1524)
				(type default)
			)
			(layer "F.SilkS")
		)
		(fp_line
			(start -0.7874 0.4064)
			(end -0.7874 -0.4064)
			(stroke
				(width 0.1524)
				(type default)
			)
			(layer "F.SilkS")
		)
		(fp_line
			(start 0.7874 -0.4064)
			(end 0.7874 0.4064)
			(stroke
				(width 0.1524)
				(type default)
			)
			(layer "F.SilkS")
		)
		(fp_line
			(start 0.7874 0.4064)
			(end -0.7874 0.4064)
			(stroke
				(width 0.1524)
				(type default)
			)
			(layer "F.SilkS")
		)
		(fp_line
			(start -0.67945 -0.305054)
			(end -0.12065 -0.305054)
			(stroke
				(width 0.1)
				(type default)
			)
			(layer "F.Fab")
		)
		(fp_line
			(start -0.67945 0.3048)
			(end -0.67945 -0.305054)
			(stroke
				(width 0.1)
				(type default)
			)
			(layer "F.Fab")
		)
		(fp_line
			(start -0.12065 -0.305054)
			(end -0.12065 -0.2794)
			(stroke
				(width 0.1)
				(type default)
			)
			(layer "F.Fab")
		)
		(fp_line
			(start -0.12065 -0.2794)
			(end 0.12065 -0.2794)
			(stroke
				(width 0.1)
				(type default)
			)
			(layer "F.Fab")
		)
		(fp_line
			(start -0.12065 0.2794)
			(end -0.12065 0.3048)
			(stroke
				(width 0.1)
				(type default)
			)
			(layer "F.Fab")
		)
		(fp_line
			(start -0.12065 0.3048)
			(end -0.67945 0.3048)
			(stroke
				(width 0.1)
				(type default)
			)
			(layer "F.Fab")
		)
		(fp_line
			(start 0.120396 0.2794)
			(end -0.12065 0.2794)
			(stroke
				(width 0.1)
				(type default)
			)
			(layer "F.Fab")
		)
		(fp_line
			(start 0.120396 0.3048)
			(end 0.120396 0.2794)
			(stroke
				(width 0.1)
				(type default)
			)
			(layer "F.Fab")
		)
		(fp_line
			(start 0.12065 -0.3048)
			(end 0.67945 -0.3048)
			(stroke
				(width 0.1)
				(type default)
			)
			(layer "F.Fab")
		)
		(fp_line
			(start 0.12065 -0.2794)
			(end 0.12065 -0.3048)
			(stroke
				(width 0.1)
				(type default)
			)
			(layer "F.Fab")
		)
		(fp_line
			(start 0.67945 -0.3048)
			(end 0.67945 0.3048)
			(stroke
				(width 0.1)
				(type default)
			)
			(layer "F.Fab")
		)
		(fp_line
			(start 0.67945 0.3048)
			(end 0.120396 0.3048)
			(stroke
				(width 0.1)
				(type default)
			)
			(layer "F.Fab")
		)
		(pad "1" smd circle
			(at -0.40005 0)
			(size 0 0)
			(layers "F.Cu" "F.Mask" "F.Paste")
			(net "USB_HUB2_TI_VDD_MRP_USB3DN_TXDP3")
		)
		(pad "2" smd circle
			(at 0.40005 0)
			(size 0 0)
			(layers "F.Cu" "F.Mask" "F.Paste")
			(net "P1V2_CPU0_USB2_DVDD12")
		)
	)
	(footprint ""
		(layer "F.Cu")
		(at 200.952608 -119.721376)
		(property "Reference" "R804"
			(at 0 0 0)
			(layer "F.SilkS")
			(hide yes)
			(effects
				(font
					(size 1.27 1.27)
				)
			)
		)
		(property "Value" ""
			(at 0 0 0)
			(layer "F.Fab")
			(effects
				(font
					(size 1.27 1.27)
				)
			)
		)
		(duplicate_pad_numbers_are_jumpers no)
		(fp_line
			(start -0.7874 -0.4064)
			(end 0.7874 -0.4064)
			(stroke
				(width 0.1524)
				(type default)
			)
			(layer "F.SilkS")
		)
		(fp_line
			(start -0.7874 0.4064)
			(end -0.7874 -0.4064)
			(stroke
				(width 0.1524)
				(type default)
			)
			(layer "F.SilkS")
		)
		(fp_line
			(start 0.7874 -0.4064)
			(end 0.7874 0.4064)
			(stroke
				(width 0.1524)
				(type default)
			)
			(layer "F.SilkS")
		)
		(fp_line
			(start 0.7874 0.4064)
			(end -0.7874 0.4064)
			(stroke
				(width 0.1524)
				(type default)
			)
			(layer "F.SilkS")
		)
		(fp_line
			(start -0.67945 -0.305054)
			(end -0.12065 -0.305054)
			(stroke
				(width 0.1)
				(type default)
			)
			(layer "F.Fab")
		)
		(fp_line
			(start -0.67945 0.3048)
			(end -0.67945 -0.305054)
			(stroke
				(width 0.1)
				(type default)
			)
			(layer "F.Fab")
		)
		(fp_line
			(start -0.12065 -0.305054)
			(end -0.12065 -0.2794)
			(stroke
				(width 0.1)
				(type default)
			)
			(layer "F.Fab")
		)
		(fp_line
			(start -0.12065 -0.2794)
			(end 0.12065 -0.2794)
			(stroke
				(width 0.1)
				(type default)
			)
			(layer "F.Fab")
		)
		(fp_line
			(start -0.12065 0.2794)
			(end -0.12065 0.3048)
			(stroke
				(width 0.1)
				(type default)
			)
			(layer "F.Fab")
		)
		(fp_line
			(start -0.12065 0.3048)
			(end -0.67945 0.3048)
			(stroke
				(width 0.1)
				(type default)
			)
			(layer "F.Fab")
		)
		(fp_line
			(start 0.120396 0.2794)
			(end -0.12065 0.2794)
			(stroke
				(width 0.1)
				(type default)
			)
			(layer "F.Fab")
		)
		(fp_line
			(start 0.120396 0.3048)
			(end 0.120396 0.2794)
			(stroke
				(width 0.1)
				(type default)
			)
			(layer "F.Fab")
		)
		(fp_line
			(start 0.12065 -0.3048)
			(end 0.67945 -0.3048)
			(stroke
				(width 0.1)
				(type default)
			)
			(layer "F.Fab")
		)
		(fp_line
			(start 0.12065 -0.2794)
			(end 0.12065 -0.3048)
			(stroke
				(width 0.1)
				(type default)
			)
			(layer "F.Fab")
		)
		(fp_line
			(start 0.67945 -0.3048)
			(end 0.67945 0.3048)
			(stroke
				(width 0.1)
				(type default)
			)
			(layer "F.Fab")
		)
		(fp_line
			(start 0.67945 0.3048)
			(end 0.120396 0.3048)
			(stroke
				(width 0.1)
				(type default)
			)
			(layer "F.Fab")
		)
		(pad "1" smd circle
			(at -0.40005 0)
			(size 0 0)
			(layers "F.Cu" "F.Mask" "F.Paste")
			(net "RST_PERST_M2_0_N")
		)
		(pad "2" smd circle
			(at 0.40005 0)
			(size 0 0)
			(layers "F.Cu" "F.Mask" "F.Paste")
			(net "GND")
		)
	)
	(footprint ""
		(layer "F.Cu")
		(at 149.606 -123.444 180)
		(property "Reference" "D8005"
			(at 3.213862 1.346962 0)
			(unlocked yes)
			(layer "F.SilkS")
			(effects
				(font
					(size 0.7874 0.5842)
					(thickness 0.1524)
				)
				(justify left)
			)
		)
		(property "Value" ""
			(at 0 0 180)
			(layer "F.Fab")
			(effects
				(font
					(size 1.27 1.27)
				)
			)
		)
		(duplicate_pad_numbers_are_jumpers no)
		(fp_line
			(start 2.343404 0.6985)
			(end 2.216404 0.6985)
			(stroke
				(width 0.1524)
				(type default)
			)
			(layer "F.SilkS")
		)
		(fp_line
			(start 2.343404 -0.6985)
			(end 2.343404 0.6985)
			(stroke
				(width 0.1524)
				(type default)
			)
			(layer "F.SilkS")
		)
		(fp_line
			(start 2.229104 0.6985)
			(end 2.051304 0.6985)
			(stroke
				(width 0.1524)
				(type default)
			)
			(layer "F.SilkS")
		)
		(fp_line
			(start 2.229104 -0.6985)
			(end 2.229104 0.6985)
			(stroke
				(width 0.1524)
				(type default)
			)
			(layer "F.SilkS")
		)
		(fp_line
			(start 2.152904 0.635)
			(end 2.152904 -0.6985)
			(stroke
				(width 0.1524)
				(type default)
			)
			(layer "F.SilkS")
		)
		(fp_line
			(start 2.152904 -0.6985)
			(end 2.343404 -0.6985)
			(stroke
				(width 0.1524)
				(type default)
			)
			(layer "F.SilkS")
		)
		(fp_line
			(start 2.064004 -0.6731)
			(end 2.064004 -0.6985)
			(stroke
				(width 0.1524)
				(type default)
			)
			(layer "F.SilkS")
		)
		(fp_line
			(start 2.064004 -0.6985)
			(end 2.229104 -0.6985)
			(stroke
				(width 0.1524)
				(type default)
			)
			(layer "F.SilkS")
		)
		(fp_line
			(start 2.051304 0.6985)
			(end 2.051304 0.635)
			(stroke
				(width 0.1524)
				(type default)
			)
			(layer "F.SilkS")
		)
		(fp_line
			(start 2.051304 0.635)
			(end 2.152904 0.635)
			(stroke
				(width 0.1524)
				(type default)
			)
			(layer "F.SilkS")
		)
		(fp_line
			(start 2.050796 0.700024)
			(end -2.050796 0.700024)
			(stroke
				(width 0.1524)
				(type default)
			)
			(layer "F.SilkS")
		)
		(fp_line
			(start 2.050796 -0.700024)
			(end 2.050796 0.700024)
			(stroke
				(width 0.1524)
				(type default)
			)
			(layer "F.SilkS")
		)
		(fp_line
			(start 0.293878 -0.500126)
			(end 0.293878 0.500126)
			(stroke
				(width 0.1524)
				(type default)
			)
			(layer "F.SilkS")
		)
		(fp_line
			(start 0.193802 0)
			(end -0.30607 -0.500126)
			(stroke
				(width 0.1524)
				(type default)
			)
			(layer "F.SilkS")
		)
		(fp_line
			(start -0.30607 0.500126)
			(end 0.193802 0)
			(stroke
				(width 0.1524)
				(type default)
			)
			(layer "F.SilkS")
		)
		(fp_line
			(start -0.30607 -0.500126)
			(end -0.30607 0.500126)
			(stroke
				(width 0.1524)
				(type default)
			)
			(layer "F.SilkS")
		)
		(fp_line
			(start -2.050796 0.700024)
			(end -2.050796 -0.700024)
			(stroke
				(width 0.1524)
				(type default)
			)
			(layer "F.SilkS")
		)
		(fp_line
			(start -2.050796 -0.700024)
			(end 2.050796 -0.700024)
			(stroke
				(width 0.1524)
				(type default)
			)
			(layer "F.SilkS")
		)
		(fp_line
			(start 0.899922 0.700024)
			(end -0.899922 0.700024)
			(stroke
				(width 0.1)
				(type default)
			)
			(layer "F.Fab")
		)
		(fp_line
			(start 0.899922 -0.700024)
			(end 0.899922 0.700024)
			(stroke
				(width 0.1)
				(type default)
			)
			(layer "F.Fab")
		)
		(fp_line
			(start -0.899922 0.700024)
			(end -0.899922 -0.700024)
			(stroke
				(width 0.1)
				(type default)
			)
			(layer "F.Fab")
		)
		(fp_line
			(start -0.899922 -0.700024)
			(end 0.899922 -0.700024)
			(stroke
				(width 0.1)
				(type default)
			)
			(layer "F.Fab")
		)
		(fp_text user "-"
			(at 3.880104 0.23495 0)
			(unlocked yes)
			(layer "F.SilkS")
			(effects
				(font
					(size 1.905 1.4224)
					(thickness 0.1524)
				)
				(justify left)
			)
		)
		(fp_text user "+"
			(at -3.362706 1.093978 270)
			(unlocked yes)
			(layer "F.SilkS")
			(effects
				(font
					(size 1.905 1.4224)
					(thickness 0.1524)
				)
				(justify left)
			)
		)
		(fp_text user "-"
			(at 3.880104 0.23495 0)
			(unlocked yes)
			(layer "F.Fab")
			(effects
				(font
					(size 1.905 1.4224)
					(thickness 0.1524)
				)
				(justify left)
			)
		)
		(fp_text user "+"
			(at -3.123946 0.762 270)
			(unlocked yes)
			(layer "F.Fab")
			(effects
				(font
					(size 1.905 1.4224)
					(thickness 0.1524)
				)
				(justify left)
			)
		)
		(pad "1" smd rect
			(at -1.199896 0 90)
			(size 0.6604 1.3716)
			(layers "F.Cu" "F.Mask" "F.Paste")
			(net "PWRGD_CHAF_CPU1_R1")
		)
		(pad "2" smd rect
			(at 1.199896 0 270)
			(size 0.6604 1.3716)
			(layers "F.Cu" "F.Mask" "F.Paste")
			(net "P3V3_AUX")
		)
	)
)
